(kicad_pcb
	(version 20260206)
	(generator "pcbnew")
	(generator_version "10.0")
	(general
		(thickness 1.6)
		(legacy_teardrops no)
	)
	(paper "A4")
	(title_block
		(title "04192023_DAF0TMB3IC0_F0TG_MB_C_brd_V02_OCP.brd")
		(comment 1 "Grand Teton / footprints 2845-2850 of 8354")
	)
	(layers
		(0 "F.Cu" signal "TOP")
		(4 "In1.Cu" signal "GND")
		(6 "In2.Cu" signal "IN1")
		(8 "In3.Cu" signal "GND1")
		(10 "In4.Cu" signal "IN2")
		(12 "In5.Cu" signal "GND2")
		(14 "In6.Cu" signal "IN3")
		(16 "In7.Cu" signal "GND3")
		(18 "In8.Cu" signal "VCC")
		(20 "In9.Cu" signal "VCC1")
		(22 "In10.Cu" signal "GND4")
		(24 "In11.Cu" signal "IN4")
		(26 "In12.Cu" signal "GND5")
		(28 "In13.Cu" signal "IN5")
		(30 "In14.Cu" signal "GND6")
		(32 "In15.Cu" signal "IN6")
		(34 "In16.Cu" signal "GND7")
		(2 "B.Cu" signal "BOTTOM")
		(9 "F.Adhes" user "F.Adhesive")
		(11 "B.Adhes" user "B.Adhesive")
		(13 "F.Paste" user "Package Geometry/Pastemask Top")
		(15 "B.Paste" user "Package Geometry/Pastemask Bottom")
		(5 "F.SilkS" user "Ref Des/Silkscreen Top")
		(7 "B.SilkS" user "Ref Des/Silkscreen Bottom")
		(1 "F.Mask" user "Board Geometry/Soldermask Top")
		(3 "B.Mask" user "Board Geometry/Soldermask Bottom")
		(17 "Dwgs.User" user "User.Drawings")
		(19 "Cmts.User" user "User.Comments")
		(21 "Eco1.User" user "User.Eco1")
		(23 "Eco2.User" user "User.Eco2")
		(25 "Edge.Cuts" user "Board Geometry/Outline")
		(27 "Margin" user)
		(31 "F.CrtYd" user "Package Geometry/Place Bound Top")
		(29 "B.CrtYd" user "Package Geometry/Place Bound Bottom")
		(35 "F.Fab" user "Ref Des/Assembly Top")
		(33 "B.Fab" user "Ref Des/Assembly Bottom")
	)
	(footprint ""
		(layer "F.Cu")
		(at 372.46687 -15.637002)
		(property "Reference" "R53"
			(at 0 0 0)
			(layer "F.SilkS")
			(hide yes)
			(effects
				(font
					(size 1.27 1.27)
				)
			)
		)
		(property "Value" ""
			(at 0 0 0)
			(layer "F.Fab")
			(effects
				(font
					(size 1.27 1.27)
				)
			)
		)
		(duplicate_pad_numbers_are_jumpers no)
		(fp_line
			(start -0.7874 -0.4064)
			(end 0.7874 -0.4064)
			(stroke
				(width 0.1524)
				(type default)
			)
			(layer "F.SilkS")
		)
		(fp_line
			(start -0.7874 0.4064)
			(end -0.7874 -0.4064)
			(stroke
				(width 0.1524)
				(type default)
			)
			(layer "F.SilkS")
		)
		(fp_line
			(start 0.7874 -0.4064)
			(end 0.7874 0.4064)
			(stroke
				(width 0.1524)
				(type default)
			)
			(layer "F.SilkS")
		)
		(fp_line
			(start 0.7874 0.4064)
			(end -0.7874 0.4064)
			(stroke
				(width 0.1524)
				(type default)
			)
			(layer "F.SilkS")
		)
		(fp_line
			(start -0.67945 -0.305054)
			(end -0.12065 -0.305054)
			(stroke
				(width 0.1)
				(type default)
			)
			(layer "F.Fab")
		)
		(fp_line
			(start -0.67945 0.3048)
			(end -0.67945 -0.305054)
			(stroke
				(width 0.1)
				(type default)
			)
			(layer "F.Fab")
		)
		(fp_line
			(start -0.12065 -0.305054)
			(end -0.12065 -0.2794)
			(stroke
				(width 0.1)
				(type default)
			)
			(layer "F.Fab")
		)
		(fp_line
			(start -0.12065 -0.2794)
			(end 0.12065 -0.2794)
			(stroke
				(width 0.1)
				(type default)
			)
			(layer "F.Fab")
		)
		(fp_line
			(start -0.12065 0.2794)
			(end -0.12065 0.3048)
			(stroke
				(width 0.1)
				(type default)
			)
			(layer "F.Fab")
		)
		(fp_line
			(start -0.12065 0.3048)
			(end -0.67945 0.3048)
			(stroke
				(width 0.1)
				(type default)
			)
			(layer "F.Fab")
		)
		(fp_line
			(start 0.120396 0.2794)
			(end -0.12065 0.2794)
			(stroke
				(width 0.1)
				(type default)
			)
			(layer "F.Fab")
		)
		(fp_line
			(start 0.120396 0.3048)
			(end 0.120396 0.2794)
			(stroke
				(width 0.1)
				(type default)
			)
			(layer "F.Fab")
		)
		(fp_line
			(start 0.12065 -0.3048)
			(end 0.67945 -0.3048)
			(stroke
				(width 0.1)
				(type default)
			)
			(layer "F.Fab")
		)
		(fp_line
			(start 0.12065 -0.2794)
			(end 0.12065 -0.3048)
			(stroke
				(width 0.1)
				(type default)
			)
			(layer "F.Fab")
		)
		(fp_line
			(start 0.67945 -0.3048)
			(end 0.67945 0.3048)
			(stroke
				(width 0.1)
				(type default)
			)
			(layer "F.Fab")
		)
		(fp_line
			(start 0.67945 0.3048)
			(end 0.120396 0.3048)
			(stroke
				(width 0.1)
				(type default)
			)
			(layer "F.Fab")
		)
		(pad "1" smd circle
			(at -0.40005 0)
			(size 0 0)
			(layers "F.Cu" "F.Mask" "F.Paste")
			(net "P3V3_AUX")
		)
		(pad "2" smd circle
			(at 0.40005 0)
			(size 0 0)
			(layers "F.Cu" "F.Mask" "F.Paste")
			(net "OCP_SFF_PWRBRK_BUFF_N")
		)
	)
	(footprint ""
		(layer "F.Cu")
		(at 197.269608 -116.673376)
		(property "Reference" "R957"
			(at 0 0 0)
			(layer "F.SilkS")
			(hide yes)
			(effects
				(font
					(size 1.27 1.27)
				)
			)
		)
		(property "Value" ""
			(at 0 0 0)
			(layer "F.Fab")
			(effects
				(font
					(size 1.27 1.27)
				)
			)
		)
		(duplicate_pad_numbers_are_jumpers no)
		(fp_line
			(start -0.7874 -0.4064)
			(end 0.7874 -0.4064)
			(stroke
				(width 0.1524)
				(type default)
			)
			(layer "F.SilkS")
		)
		(fp_line
			(start -0.7874 0.4064)
			(end -0.7874 -0.4064)
			(stroke
				(width 0.1524)
				(type default)
			)
			(layer "F.SilkS")
		)
		(fp_line
			(start 0.7874 -0.4064)
			(end 0.7874 0.4064)
			(stroke
				(width 0.1524)
				(type default)
			)
			(layer "F.SilkS")
		)
		(fp_line
			(start 0.7874 0.4064)
			(end -0.7874 0.4064)
			(stroke
				(width 0.1524)
				(type default)
			)
			(layer "F.SilkS")
		)
		(fp_line
			(start -0.67945 -0.305054)
			(end -0.12065 -0.305054)
			(stroke
				(width 0.1)
				(type default)
			)
			(layer "F.Fab")
		)
		(fp_line
			(start -0.67945 0.3048)
			(end -0.67945 -0.305054)
			(stroke
				(width 0.1)
				(type default)
			)
			(layer "F.Fab")
		)
		(fp_line
			(start -0.12065 -0.305054)
			(end -0.12065 -0.2794)
			(stroke
				(width 0.1)
				(type default)
			)
			(layer "F.Fab")
		)
		(fp_line
			(start -0.12065 -0.2794)
			(end 0.12065 -0.2794)
			(stroke
				(width 0.1)
				(type default)
			)
			(layer "F.Fab")
		)
		(fp_line
			(start -0.12065 0.2794)
			(end -0.12065 0.3048)
			(stroke
				(width 0.1)
				(type default)
			)
			(layer "F.Fab")
		)
		(fp_line
			(start -0.12065 0.3048)
			(end -0.67945 0.3048)
			(stroke
				(width 0.1)
				(type default)
			)
			(layer "F.Fab")
		)
		(fp_line
			(start 0.120396 0.2794)
			(end -0.12065 0.2794)
			(stroke
				(width 0.1)
				(type default)
			)
			(layer "F.Fab")
		)
		(fp_line
			(start 0.120396 0.3048)
			(end 0.120396 0.2794)
			(stroke
				(width 0.1)
				(type default)
			)
			(layer "F.Fab")
		)
		(fp_line
			(start 0.12065 -0.3048)
			(end 0.67945 -0.3048)
			(stroke
				(width 0.1)
				(type default)
			)
			(layer "F.Fab")
		)
		(fp_line
			(start 0.12065 -0.2794)
			(end 0.12065 -0.3048)
			(stroke
				(width 0.1)
				(type default)
			)
			(layer "F.Fab")
		)
		(fp_line
			(start 0.67945 -0.3048)
			(end 0.67945 0.3048)
			(stroke
				(width 0.1)
				(type default)
			)
			(layer "F.Fab")
		)
		(fp_line
			(start 0.67945 0.3048)
			(end 0.120396 0.3048)
			(stroke
				(width 0.1)
				(type default)
			)
			(layer "F.Fab")
		)
		(pad "1" smd circle
			(at -0.40005 0)
			(size 0 0)
			(layers "F.Cu" "F.Mask" "F.Paste")
			(net "FM_RST_PERST_SCM_R_N")
		)
		(pad "2" smd circle
			(at 0.40005 0)
			(size 0 0)
			(layers "F.Cu" "F.Mask" "F.Paste")
			(net "FM_RST_PERST_SCM_N")
		)
	)
	(footprint ""
		(layer "F.Cu")
		(at 180.528468 -53.065934)
		(property "Reference" "C1098"
			(at 0 0 0)
			(layer "F.SilkS")
			(hide yes)
			(effects
				(font
					(size 1.27 1.27)
				)
			)
		)
		(property "Value" ""
			(at 0 0 0)
			(layer "F.Fab")
			(effects
				(font
					(size 1.27 1.27)
				)
			)
		)
		(duplicate_pad_numbers_are_jumpers no)
		(fp_line
			(start -0.299974 -0.150114)
			(end 0.299974 -0.150114)
			(stroke
				(width 0.1)
				(type default)
			)
			(layer "F.Fab")
		)
		(fp_line
			(start -0.299974 0.150114)
			(end -0.299974 -0.150114)
			(stroke
				(width 0.1)
				(type default)
			)
			(layer "F.Fab")
		)
		(fp_line
			(start 0.299974 -0.150114)
			(end 0.299974 0.150114)
			(stroke
				(width 0.1)
				(type default)
			)
			(layer "F.Fab")
		)
		(fp_line
			(start 0.299974 0.150114)
			(end -0.299974 0.150114)
			(stroke
				(width 0.1)
				(type default)
			)
			(layer "F.Fab")
		)
		(pad "1" smd rect
			(at -0.2667 0)
			(size 0.3048 0.381)
			(layers "F.Cu" "F.Mask" "F.Paste")
			(net "P3E_CPU1_P4_TX_C_DP<3>")
		)
		(pad "2" smd rect
			(at 0.2667 0)
			(size 0.3048 0.381)
			(layers "F.Cu" "F.Mask" "F.Paste")
			(net "P3E_CPU1_P4_TX_DP<3>")
		)
	)
	(footprint ""
		(layer "F.Cu")
		(at 352.45548 -436.925212 -90)
		(property "Reference" "U316"
			(at 1.614424 -1.87071 90)
			(unlocked yes)
			(layer "F.SilkS")
			(effects
				(font
					(size 0.7874 0.5842)
					(thickness 0.1524)
				)
				(justify left)
			)
		)
		(property "Value" ""
			(at 0 0 270)
			(layer "F.Fab")
			(effects
				(font
					(size 1.27 1.27)
				)
			)
		)
		(duplicate_pad_numbers_are_jumpers no)
		(fp_line
			(start -1.3462 1.100074)
			(end -1.3462 -1.100074)
			(stroke
				(width 0.1524)
				(type default)
			)
			(layer "F.SilkS")
		)
		(fp_line
			(start 1.3462 1.100074)
			(end -1.3462 1.100074)
			(stroke
				(width 0.1524)
				(type default)
			)
			(layer "F.SilkS")
		)
		(fp_line
			(start 0 -0.381)
			(end 0.670052 -1.100074)
			(stroke
				(width 0.1524)
				(type default)
			)
			(layer "F.SilkS")
		)
		(fp_line
			(start -1.3462 -1.100074)
			(end -0.670052 -1.100074)
			(stroke
				(width 0.1524)
				(type default)
			)
			(layer "F.SilkS")
		)
		(fp_line
			(start -0.670052 -1.100074)
			(end 0 -0.381)
			(stroke
				(width 0.1524)
				(type default)
			)
			(layer "F.SilkS")
		)
		(fp_line
			(start 0.670052 -1.100074)
			(end 1.3462 -1.100074)
			(stroke
				(width 0.1524)
				(type default)
			)
			(layer "F.SilkS")
		)
		(fp_line
			(start 1.3462 -1.100074)
			(end 1.3462 1.100074)
			(stroke
				(width 0.1524)
				(type default)
			)
			(layer "F.SilkS")
		)
		(fp_poly
			(pts
				(xy -2.29108 -1.452372) (xy -1.752346 -1.991106) (xy -1.482852 -1.182878)
			)
			(stroke
				(width 0)
				(type default)
			)
			(fill yes)
			(layer "F.SilkS")
		)
		(fp_line
			(start -0.670052 1.100074)
			(end -0.670052 0.8001)
			(stroke
				(width 0.1)
				(type default)
			)
			(layer "F.Fab")
		)
		(fp_line
			(start 0.670052 1.100074)
			(end -0.670052 1.100074)
			(stroke
				(width 0.1)
				(type default)
			)
			(layer "F.Fab")
		)
		(fp_line
			(start -1.100074 0.8001)
			(end -1.100074 -0.8001)
			(stroke
				(width 0.1)
				(type default)
			)
			(layer "F.Fab")
		)
		(fp_line
			(start -0.670052 0.8001)
			(end -1.100074 0.8001)
			(stroke
				(width 0.1)
				(type default)
			)
			(layer "F.Fab")
		)
		(fp_line
			(start -0.670052 0.8001)
			(end -0.670052 -0.8001)
			(stroke
				(width 0.1)
				(type default)
			)
			(layer "F.Fab")
		)
		(fp_line
			(start 0.670052 0.8001)
			(end 0.670052 1.100074)
			(stroke
				(width 0.1)
				(type default)
			)
			(layer "F.Fab")
		)
		(fp_line
			(start 1.100074 0.8001)
			(end 0.670052 0.8001)
			(stroke
				(width 0.1)
				(type default)
			)
			(layer "F.Fab")
		)
		(fp_line
			(start -1.100074 -0.8001)
			(end -0.670052 -0.8001)
			(stroke
				(width 0.1)
				(type default)
			)
			(layer "F.Fab")
		)
		(fp_line
			(start -0.670052 -0.8001)
			(end -0.670052 -1.100074)
			(stroke
				(width 0.1)
				(type default)
			)
			(layer "F.Fab")
		)
		(fp_line
			(start 0.670052 -0.8001)
			(end 0.670052 0.8001)
			(stroke
				(width 0.1)
				(type default)
			)
			(layer "F.Fab")
		)
		(fp_line
			(start 0.670052 -0.8001)
			(end 1.100074 -0.8001)
			(stroke
				(width 0.1)
				(type default)
			)
			(layer "F.Fab")
		)
		(fp_line
			(start 1.100074 -0.8001)
			(end 1.100074 0.8001)
			(stroke
				(width 0.1)
				(type default)
			)
			(layer "F.Fab")
		)
		(fp_line
			(start -0.670052 -1.100074)
			(end 0.670052 -1.100074)
			(stroke
				(width 0.1)
				(type default)
			)
			(layer "F.Fab")
		)
		(fp_line
			(start 0.670052 -1.100074)
			(end 0.670052 -0.8001)
			(stroke
				(width 0.1)
				(type default)
			)
			(layer "F.Fab")
		)
		(fp_poly
			(pts
				(xy -1.524 -0.649986) (xy -2.286 -1.030986) (xy -2.286 -0.268986)
			)
			(stroke
				(width 0)
				(type default)
			)
			(fill yes)
			(layer "F.Fab")
		)
		(pad "1" smd rect
			(at -0.94996 -0.649986 180)
			(size 0.4064 0.508)
			(layers "F.Cu" "F.Mask" "F.Paste")
			(net "SWB_HSC_EN")
		)
		(pad "2" smd rect
			(at -0.94996 0 180)
			(size 0.4064 0.508)
			(layers "F.Cu" "F.Mask" "F.Paste")
			(net "GND")
		)
		(pad "3" smd rect
			(at -0.94996 0.649986 180)
			(size 0.4064 0.508)
			(layers "F.Cu" "F.Mask" "F.Paste")
			(net "GND")
		)
		(pad "4" smd rect
			(at 0.94996 0.649986 180)
			(size 0.4064 0.508)
			(layers "F.Cu" "F.Mask" "F.Paste")
			(net "NC_U316_2Y")
		)
		(pad "5" smd rect
			(at 0.94996 0 180)
			(size 0.4064 0.508)
			(layers "F.Cu" "F.Mask" "F.Paste")
			(net "P3V3_AUX")
		)
		(pad "6" smd rect
			(at 0.94996 -0.649986 180)
			(size 0.4064 0.508)
			(layers "F.Cu" "F.Mask" "F.Paste")
			(net "SWB_HSC_EN_BUF_R")
		)
	)
	(footprint ""
		(layer "F.Cu")
		(at 305.754024 -32.701992)
		(property "Reference" "R5101"
			(at 0 0 0)
			(layer "F.SilkS")
			(hide yes)
			(effects
				(font
					(size 1.27 1.27)
				)
			)
		)
		(property "Value" ""
			(at 0 0 0)
			(layer "F.Fab")
			(effects
				(font
					(size 1.27 1.27)
				)
			)
		)
		(duplicate_pad_numbers_are_jumpers no)
		(fp_line
			(start -0.7874 -0.4064)
			(end 0.7874 -0.4064)
			(stroke
				(width 0.1524)
				(type default)
			)
			(layer "F.SilkS")
		)
		(fp_line
			(start -0.7874 0.4064)
			(end -0.7874 -0.4064)
			(stroke
				(width 0.1524)
				(type default)
			)
			(layer "F.SilkS")
		)
		(fp_line
			(start 0.7874 -0.4064)
			(end 0.7874 0.4064)
			(stroke
				(width 0.1524)
				(type default)
			)
			(layer "F.SilkS")
		)
		(fp_line
			(start 0.7874 0.4064)
			(end -0.7874 0.4064)
			(stroke
				(width 0.1524)
				(type default)
			)
			(layer "F.SilkS")
		)
		(fp_line
			(start -0.67945 -0.305054)
			(end -0.12065 -0.305054)
			(stroke
				(width 0.1)
				(type default)
			)
			(layer "F.Fab")
		)
		(fp_line
			(start -0.67945 0.3048)
			(end -0.67945 -0.305054)
			(stroke
				(width 0.1)
				(type default)
			)
			(layer "F.Fab")
		)
		(fp_line
			(start -0.12065 -0.305054)
			(end -0.12065 -0.2794)
			(stroke
				(width 0.1)
				(type default)
			)
			(layer "F.Fab")
		)
		(fp_line
			(start -0.12065 -0.2794)
			(end 0.12065 -0.2794)
			(stroke
				(width 0.1)
				(type default)
			)
			(layer "F.Fab")
		)
		(fp_line
			(start -0.12065 0.2794)
			(end -0.12065 0.3048)
			(stroke
				(width 0.1)
				(type default)
			)
			(layer "F.Fab")
		)
		(fp_line
			(start -0.12065 0.3048)
			(end -0.67945 0.3048)
			(stroke
				(width 0.1)
				(type default)
			)
			(layer "F.Fab")
		)
		(fp_line
			(start 0.120396 0.2794)
			(end -0.12065 0.2794)
			(stroke
				(width 0.1)
				(type default)
			)
			(layer "F.Fab")
		)
		(fp_line
			(start 0.120396 0.3048)
			(end 0.120396 0.2794)
			(stroke
				(width 0.1)
				(type default)
			)
			(layer "F.Fab")
		)
		(fp_line
			(start 0.12065 -0.3048)
			(end 0.67945 -0.3048)
			(stroke
				(width 0.1)
				(type default)
			)
			(layer "F.Fab")
		)
		(fp_line
			(start 0.12065 -0.2794)
			(end 0.12065 -0.3048)
			(stroke
				(width 0.1)
				(type default)
			)
			(layer "F.Fab")
		)
		(fp_line
			(start 0.67945 -0.3048)
			(end 0.67945 0.3048)
			(stroke
				(width 0.1)
				(type default)
			)
			(layer "F.Fab")
		)
		(fp_line
			(start 0.67945 0.3048)
			(end 0.120396 0.3048)
			(stroke
				(width 0.1)
				(type default)
			)
			(layer "F.Fab")
		)
		(pad "1" smd circle
			(at -0.40005 0)
			(size 0 0)
			(layers "F.Cu" "F.Mask" "F.Paste")
			(net "P3V3_AUX")
		)
		(pad "2" smd circle
			(at 0.40005 0)
			(size 0 0)
			(layers "F.Cu" "F.Mask" "F.Paste")
			(net "P3V3_STBY_R")
		)
	)
	(footprint ""
		(layer "F.Cu")
		(at 70.739 -53.594)
		(property "Reference" "R1175"
			(at 0 0 0)
			(layer "F.SilkS")
			(hide yes)
			(effects
				(font
					(size 1.27 1.27)
				)
			)
		)
		(property "Value" ""
			(at 0 0 0)
			(layer "F.Fab")
			(effects
				(font
					(size 1.27 1.27)
				)
			)
		)
		(duplicate_pad_numbers_are_jumpers no)
		(fp_line
			(start -0.7874 -0.4064)
			(end 0.7874 -0.4064)
			(stroke
				(width 0.1524)
				(type default)
			)
			(layer "F.SilkS")
		)
		(fp_line
			(start -0.7874 0.4064)
			(end -0.7874 -0.4064)
			(stroke
				(width 0.1524)
				(type default)
			)
			(layer "F.SilkS")
		)
		(fp_line
			(start 0.7874 -0.4064)
			(end 0.7874 0.4064)
			(stroke
				(width 0.1524)
				(type default)
			)
			(layer "F.SilkS")
		)
		(fp_line
			(start 0.7874 0.4064)
			(end -0.7874 0.4064)
			(stroke
				(width 0.1524)
				(type default)
			)
			(layer "F.SilkS")
		)
		(fp_line
			(start -0.67945 -0.305054)
			(end -0.12065 -0.305054)
			(stroke
				(width 0.1)
				(type default)
			)
			(layer "F.Fab")
		)
		(fp_line
			(start -0.67945 0.3048)
			(end -0.67945 -0.305054)
			(stroke
				(width 0.1)
				(type default)
			)
			(layer "F.Fab")
		)
		(fp_line
			(start -0.12065 -0.305054)
			(end -0.12065 -0.2794)
			(stroke
				(width 0.1)
				(type default)
			)
			(layer "F.Fab")
		)
		(fp_line
			(start -0.12065 -0.2794)
			(end 0.12065 -0.2794)
			(stroke
				(width 0.1)
				(type default)
			)
			(layer "F.Fab")
		)
		(fp_line
			(start -0.12065 0.2794)
			(end -0.12065 0.3048)
			(stroke
				(width 0.1)
				(type default)
			)
			(layer "F.Fab")
		)
		(fp_line
			(start -0.12065 0.3048)
			(end -0.67945 0.3048)
			(stroke
				(width 0.1)
				(type default)
			)
			(layer "F.Fab")
		)
		(fp_line
			(start 0.120396 0.2794)
			(end -0.12065 0.2794)
			(stroke
				(width 0.1)
				(type default)
			)
			(layer "F.Fab")
		)
		(fp_line
			(start 0.120396 0.3048)
			(end 0.120396 0.2794)
			(stroke
				(width 0.1)
				(type default)
			)
			(layer "F.Fab")
		)
		(fp_line
			(start 0.12065 -0.3048)
			(end 0.67945 -0.3048)
			(stroke
				(width 0.1)
				(type default)
			)
			(layer "F.Fab")
		)
		(fp_line
			(start 0.12065 -0.2794)
			(end 0.12065 -0.3048)
			(stroke
				(width 0.1)
				(type default)
			)
			(layer "F.Fab")
		)
		(fp_line
			(start 0.67945 -0.3048)
			(end 0.67945 0.3048)
			(stroke
				(width 0.1)
				(type default)
			)
			(layer "F.Fab")
		)
		(fp_line
			(start 0.67945 0.3048)
			(end 0.120396 0.3048)
			(stroke
				(width 0.1)
				(type default)
			)
			(layer "F.Fab")
		)
		(pad "1" smd circle
			(at -0.40005 0)
			(size 0 0)
			(layers "F.Cu" "F.Mask" "F.Paste")
			(net "OCP_V3_2_AUX_PWR_EN_R2")
		)
		(pad "2" smd circle
			(at 0.40005 0)
			(size 0 0)
			(layers "F.Cu" "F.Mask" "F.Paste")
			(net "OCP_V3_2_AUX_PWR_EN")
		)
	)
)
